# T6G (Grand Teton) — schematic netlist excerpt (pin names and nets, part order shuffled) for the footprints in the layout excerpt that follows; sources: Cadence DE-HDL packaged netlist, KiCad conversion of 04192023_DAF0TMB3IC0_F0TG_MB_C_brd_V02_OCP.brd

PL65  Q_INDUCTOR  50NH/86A IND  pkg SMLF  page 198 : \1\ = SW_P12V_AUX_PVDDCR_SOC_P0_FLT ; \2\ = P12V_AUX
PC6546  Q_CAP  10UF 6.3V 20% X6S  pkg C0402  page 364 : A = PV09_RETIMER_CPU1_VCCS ; B = GND
PR3915  Q_RES  2K 0.1% CHIP  pkg 0402LF  page 263 : A = HSC_CS_2 ; B = AGND_HSC

(kicad_pcb
	(version 20260206)
	(generator "pcbnew")
	(generator_version "10.0")
	(general
		(thickness 1.6)
		(legacy_teardrops no)
	)
	(paper "A4")
	(title_block
		(title "04192023_DAF0TMB3IC0_F0TG_MB_C_brd_V02_OCP.brd")
		(comment 1 "Grand Teton / footprints 400-402 of 8354")
	)
	(layers
		(0 "F.Cu" signal "TOP")
		(4 "In1.Cu" signal "GND")
		(6 "In2.Cu" signal "IN1")
		(8 "In3.Cu" signal "GND1")
		(10 "In4.Cu" signal "IN2")
		(12 "In5.Cu" signal "GND2")
		(14 "In6.Cu" signal "IN3")
		(16 "In7.Cu" signal "GND3")
		(18 "In8.Cu" signal "VCC")
		(20 "In9.Cu" signal "VCC1")
		(22 "In10.Cu" signal "GND4")
		(24 "In11.Cu" signal "IN4")
		(26 "In12.Cu" signal "GND5")
		(28 "In13.Cu" signal "IN5")
		(30 "In14.Cu" signal "GND6")
		(32 "In15.Cu" signal "IN6")
		(34 "In16.Cu" signal "GND7")
		(2 "B.Cu" signal "BOTTOM")
		(9 "F.Adhes" user "F.Adhesive")
		(11 "B.Adhes" user "B.Adhesive")
		(13 "F.Paste" user "Package Geometry/Pastemask Top")
		(15 "B.Paste" user "Package Geometry/Pastemask Bottom")
		(5 "F.SilkS" user "Ref Des/Silkscreen Top")
		(7 "B.SilkS" user "Ref Des/Silkscreen Bottom")
		(1 "F.Mask" user "Board Geometry/Soldermask Top")
		(3 "B.Mask" user "Board Geometry/Soldermask Bottom")
		(17 "Dwgs.User" user "User.Drawings")
		(19 "Cmts.User" user "User.Comments")
		(21 "Eco1.User" user "User.Eco1")
		(23 "Eco2.User" user "User.Eco2")
		(25 "Edge.Cuts" user "Board Geometry/Outline")
		(27 "Margin" user)
		(31 "F.CrtYd" user "Package Geometry/Place Bound Top")
		(29 "B.CrtYd" user "Package Geometry/Place Bound Bottom")
		(35 "F.Fab" user "Ref Des/Assembly Top")
		(33 "B.Fab" user "Ref Des/Assembly Bottom")
	)
	(footprint ""
		(layer "F.Cu")
		(at 12.733782 -405.611584 -90)
		(property "Reference" "PC6546"
			(at 0 0 270)
			(layer "F.SilkS")
			(hide yes)
			(effects
				(font
					(size 1.27 1.27)
				)
			)
		)
		(property "Value" ""
			(at 0 0 270)
			(layer "F.Fab")
			(effects
				(font
					(size 1.27 1.27)
				)
			)
		)
		(duplicate_pad_numbers_are_jumpers no)
		(fp_line
			(start -0.7874 0.4064)
			(end -0.7874 -0.4064)
			(stroke
				(width 0.1524)
				(type default)
			)
			(layer "F.SilkS")
		)
		(fp_line
			(start 0.7874 0.4064)
			(end -0.7874 0.4064)
			(stroke
				(width 0.1524)
				(type default)
			)
			(layer "F.SilkS")
		)
		(fp_line
			(start -0.7874 -0.4064)
			(end 0.7874 -0.4064)
			(stroke
				(width 0.1524)
				(type default)
			)
			(layer "F.SilkS")
		)
		(fp_line
			(start 0.7874 -0.4064)
			(end 0.7874 0.4064)
			(stroke
				(width 0.1524)
				(type default)
			)
			(layer "F.SilkS")
		)
		(fp_line
			(start -0.67945 0.3048)
			(end -0.67945 -0.305054)
			(stroke
				(width 0.1)
				(type default)
			)
			(layer "F.Fab")
		)
		(fp_line
			(start -0.12065 0.3048)
			(end -0.67945 0.3048)
			(stroke
				(width 0.1)
				(type default)
			)
			(layer "F.Fab")
		)
		(fp_line
			(start 0.120396 0.3048)
			(end 0.120396 0.2794)
			(stroke
				(width 0.1)
				(type default)
			)
			(layer "F.Fab")
		)
		(fp_line
			(start 0.67945 0.3048)
			(end 0.120396 0.3048)
			(stroke
				(width 0.1)
				(type default)
			)
			(layer "F.Fab")
		)
		(fp_line
			(start -0.12065 0.2794)
			(end -0.12065 0.3048)
			(stroke
				(width 0.1)
				(type default)
			)
			(layer "F.Fab")
		)
		(fp_line
			(start 0.120396 0.2794)
			(end -0.12065 0.2794)
			(stroke
				(width 0.1)
				(type default)
			)
			(layer "F.Fab")
		)
		(fp_line
			(start -0.12065 -0.2794)
			(end 0.12065 -0.2794)
			(stroke
				(width 0.1)
				(type default)
			)
			(layer "F.Fab")
		)
		(fp_line
			(start 0.12065 -0.2794)
			(end 0.12065 -0.3048)
			(stroke
				(width 0.1)
				(type default)
			)
			(layer "F.Fab")
		)
		(fp_line
			(start 0.12065 -0.3048)
			(end 0.67945 -0.3048)
			(stroke
				(width 0.1)
				(type default)
			)
			(layer "F.Fab")
		)
		(fp_line
			(start 0.67945 -0.3048)
			(end 0.67945 0.3048)
			(stroke
				(width 0.1)
				(type default)
			)
			(layer "F.Fab")
		)
		(fp_line
			(start -0.67945 -0.305054)
			(end -0.12065 -0.305054)
			(stroke
				(width 0.1)
				(type default)
			)
			(layer "F.Fab")
		)
		(fp_line
			(start -0.12065 -0.305054)
			(end -0.12065 -0.2794)
			(stroke
				(width 0.1)
				(type default)
			)
			(layer "F.Fab")
		)
		(pad "1" smd circle
			(at -0.40005 0 270)
			(size 0 0)
			(layers "F.Cu" "F.Mask" "F.Paste")
			(net "PV09_RETIMER_CPU1_VCCS")
		)
		(pad "2" smd circle
			(at 0.40005 0 270)
			(size 0 0)
			(layers "F.Cu" "F.Mask" "F.Paste")
			(net "GND")
		)
	)
	(footprint ""
		(layer "F.Cu")
		(at 204.7621 -400.972782 180)
		(property "Reference" "PR3915"
			(at 0 0 180)
			(layer "F.SilkS")
			(hide yes)
			(effects
				(font
					(size 1.27 1.27)
				)
			)
		)
		(property "Value" ""
			(at 0 0 180)
			(layer "F.Fab")
			(effects
				(font
					(size 1.27 1.27)
				)
			)
		)
		(duplicate_pad_numbers_are_jumpers no)
		(fp_line
			(start 0.7874 0.4064)
			(end -0.7874 0.4064)
			(stroke
				(width 0.1524)
				(type default)
			)
			(layer "F.SilkS")
		)
		(fp_line
			(start 0.7874 -0.4064)
			(end 0.7874 0.4064)
			(stroke
				(width 0.1524)
				(type default)
			)
			(layer "F.SilkS")
		)
		(fp_line
			(start -0.7874 0.4064)
			(end -0.7874 -0.4064)
			(stroke
				(width 0.1524)
				(type default)
			)
			(layer "F.SilkS")
		)
		(fp_line
			(start -0.7874 -0.4064)
			(end 0.7874 -0.4064)
			(stroke
				(width 0.1524)
				(type default)
			)
			(layer "F.SilkS")
		)
		(fp_line
			(start 0.67945 0.3048)
			(end 0.120396 0.3048)
			(stroke
				(width 0.1)
				(type default)
			)
			(layer "F.Fab")
		)
		(fp_line
			(start 0.67945 -0.3048)
			(end 0.67945 0.3048)
			(stroke
				(width 0.1)
				(type default)
			)
			(layer "F.Fab")
		)
		(fp_line
			(start 0.12065 -0.2794)
			(end 0.12065 -0.3048)
			(stroke
				(width 0.1)
				(type default)
			)
			(layer "F.Fab")
		)
		(fp_line
			(start 0.12065 -0.3048)
			(end 0.67945 -0.3048)
			(stroke
				(width 0.1)
				(type default)
			)
			(layer "F.Fab")
		)
		(fp_line
			(start 0.120396 0.3048)
			(end 0.120396 0.2794)
			(stroke
				(width 0.1)
				(type default)
			)
			(layer "F.Fab")
		)
		(fp_line
			(start 0.120396 0.2794)
			(end -0.12065 0.2794)
			(stroke
				(width 0.1)
				(type default)
			)
			(layer "F.Fab")
		)
		(fp_line
			(start -0.12065 0.3048)
			(end -0.67945 0.3048)
			(stroke
				(width 0.1)
				(type default)
			)
			(layer "F.Fab")
		)
		(fp_line
			(start -0.12065 0.2794)
			(end -0.12065 0.3048)
			(stroke
				(width 0.1)
				(type default)
			)
			(layer "F.Fab")
		)
		(fp_line
			(start -0.12065 -0.2794)
			(end 0.12065 -0.2794)
			(stroke
				(width 0.1)
				(type default)
			)
			(layer "F.Fab")
		)
		(fp_line
			(start -0.12065 -0.305054)
			(end -0.12065 -0.2794)
			(stroke
				(width 0.1)
				(type default)
			)
			(layer "F.Fab")
		)
		(fp_line
			(start -0.67945 0.3048)
			(end -0.67945 -0.305054)
			(stroke
				(width 0.1)
				(type default)
			)
			(layer "F.Fab")
		)
		(fp_line
			(start -0.67945 -0.305054)
			(end -0.12065 -0.305054)
			(stroke
				(width 0.1)
				(type default)
			)
			(layer "F.Fab")
		)
		(pad "1" smd circle
			(at -0.40005 0 180)
			(size 0 0)
			(layers "F.Cu" "F.Mask" "F.Paste")
			(net "HSC_CS_2")
		)
		(pad "2" smd circle
			(at 0.40005 0 180)
			(size 0 0)
			(layers "F.Cu" "F.Mask" "F.Paste")
			(net "AGND_HSC")
		)
	)
	(footprint ""
		(layer "F.Cu")
		(at 383.557018 -154.771852 180)
		(property "Reference" "PL65"
			(at 2.980436 3.704844 0)
			(unlocked yes)
			(layer "F.SilkS")
			(effects
				(font
					(size 0.7874 0.5842)
					(thickness 0.1524)
				)
				(justify left)
			)
		)
		(property "Value" ""
			(at 0 0 180)
			(layer "F.Fab")
			(effects
				(font
					(size 1.27 1.27)
				)
			)
		)
		(duplicate_pad_numbers_are_jumpers no)
		(fp_line
			(start 3.050032 2.999994)
			(end 3.050032 1.4478)
			(stroke
				(width 0.1524)
				(type default)
			)
			(layer "F.SilkS")
		)
		(fp_line
			(start 3.050032 -1.4478)
			(end 3.050032 -2.999994)
			(stroke
				(width 0.1524)
				(type default)
			)
			(layer "F.SilkS")
		)
		(fp_line
			(start 3.050032 -2.999994)
			(end -3.050032 -2.999994)
			(stroke
				(width 0.1524)
				(type default)
			)
			(layer "F.SilkS")
		)
		(fp_line
			(start -3.050032 2.999994)
			(end 3.050032 2.999994)
			(stroke
				(width 0.1524)
				(type default)
			)
			(layer "F.SilkS")
		)
		(fp_line
			(start -3.050032 1.4478)
			(end -3.050032 2.999994)
			(stroke
				(width 0.1524)
				(type default)
			)
			(layer "F.SilkS")
		)
		(fp_line
			(start -3.050032 -2.999994)
			(end -3.050032 -1.4478)
			(stroke
				(width 0.1524)
				(type default)
			)
			(layer "F.SilkS")
		)
		(fp_line
			(start 3.050032 2.999994)
			(end 3.050032 -2.999994)
			(stroke
				(width 0.1)
				(type default)
			)
			(layer "F.Fab")
		)
		(fp_line
			(start 3.050032 -2.999994)
			(end -3.050032 -2.999994)
			(stroke
				(width 0.1)
				(type default)
			)
			(layer "F.Fab")
		)
		(fp_line
			(start -3.050032 2.999994)
			(end 3.050032 2.999994)
			(stroke
				(width 0.1)
				(type default)
			)
			(layer "F.Fab")
		)
		(fp_line
			(start -3.050032 -2.999994)
			(end -3.050032 2.999994)
			(stroke
				(width 0.1)
				(type default)
			)
			(layer "F.Fab")
		)
		(pad "1" smd rect
			(at -2.525014 0 180)
			(size 1.651 2.6162)
			(layers "F.Cu" "F.Mask" "F.Paste")
			(net "SW_P12V_AUX_PVDDCR_SOC_P0_FLT")
		)
		(pad "2" smd rect
			(at 2.525014 0 180)
			(size 1.651 2.6162)
			(layers "F.Cu" "F.Mask" "F.Paste")
			(net "P12V_AUX")
		)
	)
)
